(kicad_pcb
	(version 20260206)
	(generator "pcbnew")
	(generator_version "10.0")
	(general
		(thickness 1.6)
		(legacy_teardrops no)
	)
	(paper "A4")
	(title_block
		(title "fcb — 12433-1M.1206WZS1330.brd")
		(comment 1 "Open Vault / Knox (Wiwynn) / footprints 358-364 of 495")
	)
	(layers
		(0 "F.Cu" signal "TOP")
		(4 "In1.Cu" signal "L2GND")
		(6 "In2.Cu" signal "L3VCC")
		(2 "B.Cu" signal "BOTTOM")
		(9 "F.Adhes" user "F.Adhesive")
		(11 "B.Adhes" user "B.Adhesive")
		(13 "F.Paste" user "Package Geometry/Pastemask Top")
		(15 "B.Paste" user "Package Geometry/Pastemask Bottom")
		(5 "F.SilkS" user "Ref Des/Silkscreen Top")
		(7 "B.SilkS" user "Ref Des/Silkscreen Bottom")
		(1 "F.Mask" user "Board Geometry/Soldermask Top")
		(3 "B.Mask" user "Board Geometry/Soldermask Bottom")
		(17 "Dwgs.User" user "User.Drawings")
		(19 "Cmts.User" user "User.Comments")
		(21 "Eco1.User" user "User.Eco1")
		(23 "Eco2.User" user "User.Eco2")
		(25 "Edge.Cuts" user "Board Geometry/Outline")
		(27 "Margin" user)
		(31 "F.CrtYd" user "Package Geometry/Place Bound Top")
		(29 "B.CrtYd" user "Package Geometry/Place Bound Bottom")
		(35 "F.Fab" user "Ref Des/Assembly Top")
		(33 "B.Fab" user "Ref Des/Assembly Bottom")
	)
	(footprint ""
		(layer "F.Cu")
		(at 5.1562 -417.6522 90)
		(property "Reference" "R27"
			(at 0 0 90)
			(layer "F.SilkS")
			(hide yes)
			(effects
				(font
					(size 1.27 1.27)
				)
			)
		)
		(property "Value" "33R2F-3-GP"
			(at 0.064008 -3.993896 90)
			(unlocked yes)
			(layer "F.Fab")
			(hide yes)
			(effects
				(font
					(size 1.016 1.016)
					(thickness 0.1524)
				)
			)
		)
		(property "Device Type" "R402H16"
			(at 0.064008 -5.517896 90)
			(unlocked yes)
			(layer "F.Fab")
			(hide yes)
			(effects
				(font
					(size 1.016 1.016)
					(thickness 0.1524)
				)
			)
		)
		(duplicate_pad_numbers_are_jumpers no)
		(fp_line
			(start 0.508 -0.9398)
			(end -0.508 -0.9398)
			(stroke
				(width 0.1524)
				(type default)
			)
			(layer "F.SilkS")
		)
		(fp_line
			(start -0.508 -0.9398)
			(end -0.508 0.9398)
			(stroke
				(width 0.1524)
				(type default)
			)
			(layer "F.SilkS")
		)
		(fp_rect
			(start -0.508 0.9398)
			(end 0.508 -0.9398)
			(stroke
				(width 0)
				(type default)
			)
			(fill no)
			(layer "F.CrtYd")
		)
		(fp_rect
			(start -0.508 0.9398)
			(end 0.508 -0.9398)
			(stroke
				(width 0)
				(type default)
			)
			(fill no)
			(layer "F.Fab")
		)
		(pad "1" smd custom
			(at 0 -0.4445 90)
			(size 0.1397 0.1397)
			(layers "F.Cu" "F.Mask" "F.Paste")
			(net "P3V3")
			(options
				(clearance outline)
				(anchor circle)
			)
			(primitives
				(gr_poly
					(pts
						(arc
							(start -0.1778 -0.2794)
							(mid -0.249642 -0.249642)
							(end -0.2794 -0.1778)
						)
						(arc
							(start -0.2794 0.1778)
							(mid -0.249642 0.249642)
							(end -0.1778 0.2794)
						)
						(arc
							(start 0.1778 0.2794)
							(mid 0.249642 0.249642)
							(end 0.2794 0.1778)
						)
						(arc
							(start 0.2794 -0.1778)
							(mid 0.249642 -0.249642)
							(end 0.1778 -0.2794)
						)
					)
					(width 0)
					(fill yes)
				)
			)
		)
		(pad "2" smd custom
			(at 0 0.4445 90)
			(size 0.1397 0.1397)
			(layers "F.Cu" "F.Mask" "F.Paste")
			(net "LED_DR_LED1_BLUE")
			(options
				(clearance outline)
				(anchor circle)
			)
			(primitives
				(gr_poly
					(pts
						(arc
							(start -0.1778 -0.2794)
							(mid -0.249642 -0.249642)
							(end -0.2794 -0.1778)
						)
						(arc
							(start -0.2794 0.1778)
							(mid -0.249642 0.249642)
							(end -0.1778 0.2794)
						)
						(arc
							(start 0.1778 0.2794)
							(mid 0.249642 0.249642)
							(end 0.2794 0.1778)
						)
						(arc
							(start 0.2794 -0.1778)
							(mid 0.249642 -0.249642)
							(end 0.1778 -0.2794)
						)
					)
					(width 0)
					(fill yes)
				)
			)
		)
	)
	(footprint ""
		(layer "F.Cu")
		(at 40.999918 -450.44995 90)
		(property "Reference" "PAD2"
			(at 0 0 90)
			(layer "F.SilkS")
			(hide yes)
			(effects
				(font
					(size 1.27 1.27)
				)
			)
		)
		(property "Value" "PAD-1P-424137-1-OG-GP"
			(at -22.9743 -0.4572 90)
			(unlocked yes)
			(layer "F.Fab")
			(hide yes)
			(effects
				(font
					(size 1.016 1.016)
					(thickness 0.1524)
				)
			)
		)
		(property "Device Type" "PAD-1P-424137-1-OG"
			(at -22.9743 -1.9812 90)
			(unlocked yes)
			(layer "F.Fab")
			(hide yes)
			(effects
				(font
					(size 1.016 1.016)
					(thickness 0.1524)
				)
			)
		)
		(duplicate_pad_numbers_are_jumpers no)
		(fp_line
			(start 21.4503 -7.0993)
			(end 21.4503 7.0993)
			(stroke
				(width 0.1524)
				(type default)
			)
			(layer "F.SilkS")
		)
		(fp_line
			(start 2.816098 -7.0993)
			(end 21.4503 -7.0993)
			(stroke
				(width 0.1524)
				(type default)
			)
			(layer "F.SilkS")
		)
		(fp_line
			(start -0.075946 -7.0993)
			(end -0.075946 -5.750052)
			(stroke
				(width 0.1524)
				(type default)
			)
			(layer "F.SilkS")
		)
		(fp_line
			(start -21.4503 -7.0993)
			(end -0.075946 -7.0993)
			(stroke
				(width 0.1524)
				(type default)
			)
			(layer "F.SilkS")
		)
		(fp_line
			(start 2.816098 -5.750052)
			(end 2.816098 -7.0993)
			(stroke
				(width 0.1524)
				(type default)
			)
			(layer "F.SilkS")
		)
		(fp_line
			(start 21.4503 7.0993)
			(end -21.4503 7.0993)
			(stroke
				(width 0.1524)
				(type default)
			)
			(layer "F.SilkS")
		)
		(fp_line
			(start -21.4503 7.0993)
			(end -21.4503 -7.0993)
			(stroke
				(width 0.1524)
				(type default)
			)
			(layer "F.SilkS")
		)
		(fp_arc
			(start 2.816098 -5.750052)
			(mid 1.37008 -4.30403)
			(end -0.075946 -5.750052)
			(stroke
				(width 0.1524)
				(type default)
			)
			(layer "F.SilkS")
		)
		(fp_poly
			(pts
				(xy -21.7043 7.3533) (xy -21.7043 -7.3533) (xy 0.178054 -7.3533)
				(arc
					(start 0.178054 -5.750052)
					(mid 1.370076 -4.55803)
					(end 2.562098 -5.750052)
				)
				(xy 2.562098 -7.3533) (xy 21.7043 -7.3533) (xy 21.7043 7.3533)
			)
			(stroke
				(width 0)
				(type default)
			)
			(fill no)
			(layer "F.CrtYd")
		)
		(fp_poly
			(pts
				(xy -21.7043 7.3533) (xy -21.7043 -7.3533) (xy 0.178054 -7.3533)
				(arc
					(start 0.178054 -5.750052)
					(mid 1.370076 -4.55803)
					(end 2.562098 -5.750052)
				)
				(xy 2.562098 -7.3533) (xy 21.7043 -7.3533) (xy 21.7043 7.3533)
			)
			(stroke
				(width 0)
				(type default)
			)
			(fill no)
			(layer "F.Fab")
		)
		(pad "1" smd custom
			(at 0 0 90)
			(size 3.425063 3.425063)
			(layers "F.Cu" "F.Mask" "F.Paste")
			(net "GND")
			(options
				(clearance outline)
				(anchor circle)
			)
			(primitives
				(gr_poly
					(pts
						(xy -0.329946 -6.850126) (xy -21.20011 -6.850126) (xy -21.20011 6.850126) (xy 21.20011 6.850126)
						(xy 21.20011 -6.850126) (xy 3.070098 -6.850126)
						(arc
							(start 3.070098 -5.750052)
							(mid 1.370076 -4.05003)
							(end -0.329946 -5.750052)
						)
					)
					(width 0)
					(fill yes)
				)
			)
		)
	)
	(footprint ""
		(layer "F.Cu")
		(at 15.3924 -49.0982 180)
		(property "Reference" "R184"
			(at 0 0 180)
			(layer "F.SilkS")
			(hide yes)
			(effects
				(font
					(size 1.27 1.27)
				)
			)
		)
		(property "Value" "0R2J-2-GP"
			(at 0.064008 -3.993896 180)
			(unlocked yes)
			(layer "F.Fab")
			(hide yes)
			(effects
				(font
					(size 1.016 1.016)
					(thickness 0.1524)
				)
			)
		)
		(property "Device Type" "R402H16"
			(at 0.064008 -5.517896 180)
			(unlocked yes)
			(layer "F.Fab")
			(hide yes)
			(effects
				(font
					(size 1.016 1.016)
					(thickness 0.1524)
				)
			)
		)
		(duplicate_pad_numbers_are_jumpers no)
		(fp_line
			(start 0.508 -0.9398)
			(end -0.508 -0.9398)
			(stroke
				(width 0.1524)
				(type default)
			)
			(layer "F.SilkS")
		)
		(fp_line
			(start -0.508 -0.9398)
			(end -0.508 0.9398)
			(stroke
				(width 0.1524)
				(type default)
			)
			(layer "F.SilkS")
		)
		(fp_rect
			(start -0.508 0.9398)
			(end 0.508 -0.9398)
			(stroke
				(width 0)
				(type default)
			)
			(fill no)
			(layer "F.CrtYd")
		)
		(fp_rect
			(start -0.508 0.9398)
			(end 0.508 -0.9398)
			(stroke
				(width 0)
				(type default)
			)
			(fill no)
			(layer "F.Fab")
		)
		(pad "1" smd custom
			(at 0 -0.4445 180)
			(size 0.1397 0.1397)
			(layers "F.Cu" "F.Mask" "F.Paste")
			(net "SD_LATCH_RELEASE_L")
			(options
				(clearance outline)
				(anchor circle)
			)
			(primitives
				(gr_poly
					(pts
						(arc
							(start -0.1778 -0.2794)
							(mid -0.249642 -0.249642)
							(end -0.2794 -0.1778)
						)
						(arc
							(start -0.2794 0.1778)
							(mid -0.249642 0.249642)
							(end -0.1778 0.2794)
						)
						(arc
							(start 0.1778 0.2794)
							(mid 0.249642 0.249642)
							(end 0.2794 0.1778)
						)
						(arc
							(start 0.2794 -0.1778)
							(mid 0.249642 -0.249642)
							(end 0.1778 -0.2794)
						)
					)
					(width 0)
					(fill yes)
				)
			)
		)
		(pad "2" smd custom
			(at 0 0.4445 180)
			(size 0.1397 0.1397)
			(layers "F.Cu" "F.Mask" "F.Paste")
			(net "TEMP_ALM#_REVERSE_R")
			(options
				(clearance outline)
				(anchor circle)
			)
			(primitives
				(gr_poly
					(pts
						(arc
							(start -0.1778 -0.2794)
							(mid -0.249642 -0.249642)
							(end -0.2794 -0.1778)
						)
						(arc
							(start -0.2794 0.1778)
							(mid -0.249642 0.249642)
							(end -0.1778 0.2794)
						)
						(arc
							(start 0.1778 0.2794)
							(mid 0.249642 0.249642)
							(end 0.2794 0.1778)
						)
						(arc
							(start 0.2794 -0.1778)
							(mid 0.249642 -0.249642)
							(end 0.1778 -0.2794)
						)
					)
					(width 0)
					(fill yes)
				)
			)
		)
	)
	(footprint ""
		(layer "F.Cu")
		(at 28.702 -195.3514 90)
		(property "Reference" "C42"
			(at 0 0 90)
			(layer "F.SilkS")
			(hide yes)
			(effects
				(font
					(size 1.27 1.27)
				)
			)
		)
		(property "Value" "SC1U25V3KX-1-GP"
			(at 0 -2.8194 90)
			(unlocked yes)
			(layer "F.Fab")
			(hide yes)
			(effects
				(font
					(size 1.016 1.016)
					(thickness 0.1524)
				)
			)
		)
		(property "Device Type" "C603H36"
			(at 0 -4.3434 90)
			(unlocked yes)
			(layer "F.Fab")
			(hide yes)
			(effects
				(font
					(size 1.016 1.016)
					(thickness 0.1524)
				)
			)
		)
		(duplicate_pad_numbers_are_jumpers no)
		(fp_line
			(start 0.508 0)
			(end -0.508 0)
			(stroke
				(width 0.2032)
				(type default)
			)
			(layer "F.SilkS")
		)
		(fp_rect
			(start -0.5842 1.3335)
			(end 0.5842 -1.3335)
			(stroke
				(width 0)
				(type default)
			)
			(fill no)
			(layer "F.CrtYd")
		)
		(fp_rect
			(start -0.5842 1.3335)
			(end 0.5842 -1.3335)
			(stroke
				(width 0)
				(type default)
			)
			(fill no)
			(layer "F.Fab")
		)
		(pad "1" smd custom
			(at 0 -0.762 90)
			(size 0.2159 0.2159)
			(layers "F.Cu" "F.Mask" "F.Paste")
			(net "P12V")
			(options
				(clearance outline)
				(anchor circle)
			)
			(primitives
				(gr_poly
					(pts
						(arc
							(start -0.3302 -0.4318)
							(mid -0.402042 -0.402042)
							(end -0.4318 -0.3302)
						)
						(arc
							(start -0.4318 0.3302)
							(mid -0.402042 0.402042)
							(end -0.3302 0.4318)
						)
						(arc
							(start 0.3302 0.4318)
							(mid 0.402042 0.402042)
							(end 0.4318 0.3302)
						)
						(arc
							(start 0.4318 -0.3302)
							(mid 0.402042 -0.402042)
							(end 0.3302 -0.4318)
						)
					)
					(width 0)
					(fill yes)
				)
			)
		)
		(pad "2" smd custom
			(at 0 0.762 90)
			(size 0.2159 0.2159)
			(layers "F.Cu" "F.Mask" "F.Paste")
			(net "GND")
			(options
				(clearance outline)
				(anchor circle)
			)
			(primitives
				(gr_poly
					(pts
						(arc
							(start -0.3302 -0.4318)
							(mid -0.402042 -0.402042)
							(end -0.4318 -0.3302)
						)
						(arc
							(start -0.4318 0.3302)
							(mid -0.402042 0.402042)
							(end -0.3302 0.4318)
						)
						(arc
							(start 0.3302 0.4318)
							(mid 0.402042 0.402042)
							(end 0.4318 0.3302)
						)
						(arc
							(start 0.4318 -0.3302)
							(mid 0.402042 -0.402042)
							(end 0.3302 -0.4318)
						)
					)
					(width 0)
					(fill yes)
				)
			)
		)
	)
	(footprint ""
		(layer "F.Cu")
		(at 48.895 -111.633 90)
		(property "Reference" "PR119"
			(at 0 0 90)
			(layer "F.SilkS")
			(hide yes)
			(effects
				(font
					(size 1.27 1.27)
				)
			)
		)
		(property "Value" "10R2F-L-GP"
			(at 0.064008 -3.993896 90)
			(unlocked yes)
			(layer "F.Fab")
			(hide yes)
			(effects
				(font
					(size 1.016 1.016)
					(thickness 0.1524)
				)
			)
		)
		(property "Device Type" "R402H14"
			(at 0.064008 -5.517896 90)
			(unlocked yes)
			(layer "F.Fab")
			(hide yes)
			(effects
				(font
					(size 1.016 1.016)
					(thickness 0.1524)
				)
			)
		)
		(duplicate_pad_numbers_are_jumpers no)
		(fp_line
			(start 0.508 -0.9398)
			(end -0.508 -0.9398)
			(stroke
				(width 0.1524)
				(type default)
			)
			(layer "F.SilkS")
		)
		(fp_line
			(start -0.508 -0.9398)
			(end -0.508 0.9398)
			(stroke
				(width 0.1524)
				(type default)
			)
			(layer "F.SilkS")
		)
		(fp_rect
			(start -0.508 0.9398)
			(end 0.508 -0.9398)
			(stroke
				(width 0)
				(type default)
			)
			(fill no)
			(layer "F.CrtYd")
		)
		(fp_rect
			(start -0.508 0.9398)
			(end 0.508 -0.9398)
			(stroke
				(width 0)
				(type default)
			)
			(fill no)
			(layer "F.Fab")
		)
		(pad "1" smd custom
			(at 0 -0.4445 90)
			(size 0.1397 0.1397)
			(layers "F.Cu" "F.Mask" "F.Paste")
			(net "P12VL_2490_GATE_DRV_2")
			(options
				(clearance outline)
				(anchor circle)
			)
			(primitives
				(gr_poly
					(pts
						(arc
							(start -0.1778 -0.2794)
							(mid -0.249642 -0.249642)
							(end -0.2794 -0.1778)
						)
						(arc
							(start -0.2794 0.1778)
							(mid -0.249642 0.249642)
							(end -0.1778 0.2794)
						)
						(arc
							(start 0.1778 0.2794)
							(mid 0.249642 0.249642)
							(end 0.2794 0.1778)
						)
						(arc
							(start 0.2794 -0.1778)
							(mid 0.249642 -0.249642)
							(end 0.1778 -0.2794)
						)
					)
					(width 0)
					(fill yes)
				)
			)
		)
		(pad "2" smd custom
			(at 0 0.4445 90)
			(size 0.1397 0.1397)
			(layers "F.Cu" "F.Mask" "F.Paste")
			(net "P12VL_2490_GATE")
			(options
				(clearance outline)
				(anchor circle)
			)
			(primitives
				(gr_poly
					(pts
						(arc
							(start -0.1778 -0.2794)
							(mid -0.249642 -0.249642)
							(end -0.2794 -0.1778)
						)
						(arc
							(start -0.2794 0.1778)
							(mid -0.249642 0.249642)
							(end -0.1778 0.2794)
						)
						(arc
							(start 0.1778 0.2794)
							(mid 0.249642 0.249642)
							(end 0.2794 0.1778)
						)
						(arc
							(start 0.2794 -0.1778)
							(mid 0.249642 -0.249642)
							(end 0.1778 -0.2794)
						)
					)
					(width 0)
					(fill yes)
				)
			)
		)
	)
	(footprint ""
		(layer "F.Cu")
		(at 25.5016 -140.5382 90)
		(property "Reference" "PC85"
			(at 0 0 90)
			(layer "F.SilkS")
			(hide yes)
			(effects
				(font
					(size 1.27 1.27)
				)
			)
		)
		(property "Value" "SCD01U25V2KX-3GP"
			(at 1.1811 -2.7051 90)
			(unlocked yes)
			(layer "F.Fab")
			(hide yes)
			(effects
				(font
					(size 1.016 1.016)
					(thickness 0.1524)
				)
			)
		)
		(property "Device Type" "C402H22"
			(at 1.1811 -4.2291 90)
			(unlocked yes)
			(layer "F.Fab")
			(hide yes)
			(effects
				(font
					(size 1.016 1.016)
					(thickness 0.1524)
				)
			)
		)
		(duplicate_pad_numbers_are_jumpers no)
		(fp_rect
			(start -0.4318 0.9525)
			(end 0.4318 -0.9525)
			(stroke
				(width 0)
				(type default)
			)
			(fill no)
			(layer "F.CrtYd")
		)
		(fp_rect
			(start -0.4318 0.9525)
			(end 0.4318 -0.9525)
			(stroke
				(width 0)
				(type default)
			)
			(fill no)
			(layer "F.Fab")
		)
		(pad "1" smd custom
			(at 0 -0.4445 90)
			(size 0.1524 0.1524)
			(layers "F.Cu" "F.Mask" "F.Paste")
			(net "P12VU_2490_RC")
			(options
				(clearance outline)
				(anchor circle)
			)
			(primitives
				(gr_poly
					(pts
						(arc
							(start 0.3048 -0.2032)
							(mid 0.275042 -0.275042)
							(end 0.2032 -0.3048)
						)
						(arc
							(start -0.2032 -0.3048)
							(mid -0.275042 -0.275042)
							(end -0.3048 -0.2032)
						)
						(arc
							(start -0.3048 0.2032)
							(mid -0.275042 0.275042)
							(end -0.2032 0.3048)
						)
						(arc
							(start 0.2032 0.3048)
							(mid 0.275042 0.275042)
							(end 0.3048 0.2032)
						)
					)
					(width 0)
					(fill yes)
				)
			)
		)
		(pad "2" smd custom
			(at 0 0.4445 90)
			(size 0.1524 0.1524)
			(layers "F.Cu" "F.Mask" "F.Paste")
			(net "GND")
			(options
				(clearance outline)
				(anchor circle)
			)
			(primitives
				(gr_poly
					(pts
						(arc
							(start 0.3048 -0.2032)
							(mid 0.275042 -0.275042)
							(end 0.2032 -0.3048)
						)
						(arc
							(start -0.2032 -0.3048)
							(mid -0.275042 -0.275042)
							(end -0.3048 -0.2032)
						)
						(arc
							(start -0.3048 0.2032)
							(mid -0.275042 0.275042)
							(end -0.2032 0.3048)
						)
						(arc
							(start 0.2032 0.3048)
							(mid 0.275042 0.275042)
							(end 0.3048 0.2032)
						)
					)
					(width 0)
					(fill yes)
				)
			)
		)
	)
	(footprint ""
		(layer "F.Cu")
		(at 32.9946 -251.3838 180)
		(property "Reference" "C19"
			(at 0 0 180)
			(layer "F.SilkS")
			(hide yes)
			(effects
				(font
					(size 1.27 1.27)
				)
			)
		)
		(property "Value" "SC1U16V3KX-5GP"
			(at 0 -2.8194 180)
			(unlocked yes)
			(layer "F.Fab")
			(hide yes)
			(effects
				(font
					(size 1.016 1.016)
					(thickness 0.1524)
				)
			)
		)
		(property "Device Type" "C603H36"
			(at 0 -4.3434 180)
			(unlocked yes)
			(layer "F.Fab")
			(hide yes)
			(effects
				(font
					(size 1.016 1.016)
					(thickness 0.1524)
				)
			)
		)
		(duplicate_pad_numbers_are_jumpers no)
		(fp_line
			(start 0.508 0)
			(end -0.508 0)
			(stroke
				(width 0.2032)
				(type default)
			)
			(layer "F.SilkS")
		)
		(fp_rect
			(start -0.5842 1.3335)
			(end 0.5842 -1.3335)
			(stroke
				(width 0)
				(type default)
			)
			(fill no)
			(layer "F.CrtYd")
		)
		(fp_rect
			(start -0.5842 1.3335)
			(end 0.5842 -1.3335)
			(stroke
				(width 0)
				(type default)
			)
			(fill no)
			(layer "F.Fab")
		)
		(pad "1" smd custom
			(at 0 -0.762 180)
			(size 0.2159 0.2159)
			(layers "F.Cu" "F.Mask" "F.Paste")
			(net "P3V3")
			(options
				(clearance outline)
				(anchor circle)
			)
			(primitives
				(gr_poly
					(pts
						(arc
							(start -0.3302 -0.4318)
							(mid -0.402042 -0.402042)
							(end -0.4318 -0.3302)
						)
						(arc
							(start -0.4318 0.3302)
							(mid -0.402042 0.402042)
							(end -0.3302 0.4318)
						)
						(arc
							(start 0.3302 0.4318)
							(mid 0.402042 0.402042)
							(end 0.4318 0.3302)
						)
						(arc
							(start 0.4318 -0.3302)
							(mid 0.402042 -0.402042)
							(end 0.3302 -0.4318)
						)
					)
					(width 0)
					(fill yes)
				)
			)
		)
		(pad "2" smd custom
			(at 0 0.762 180)
			(size 0.2159 0.2159)
			(layers "F.Cu" "F.Mask" "F.Paste")
			(net "GND")
			(options
				(clearance outline)
				(anchor circle)
			)
			(primitives
				(gr_poly
					(pts
						(arc
							(start -0.3302 -0.4318)
							(mid -0.402042 -0.402042)
							(end -0.4318 -0.3302)
						)
						(arc
							(start -0.4318 0.3302)
							(mid -0.402042 0.402042)
							(end -0.3302 0.4318)
						)
						(arc
							(start 0.3302 0.4318)
							(mid 0.402042 0.402042)
							(end 0.4318 0.3302)
						)
						(arc
							(start 0.4318 -0.3302)
							(mid 0.402042 -0.402042)
							(end 0.3302 -0.4318)
						)
					)
					(width 0)
					(fill yes)
				)
			)
		)
	)
)
